FILE_TYPE = MULTI_PHYS_TABLE;

PART 'M24128BWMN6TP'

{========================================================================================}
:VALUE            | PART_TYPE | MATERIAL | PART_NUMBER    = STANDARD | LIFECYCLE      | PART_NUMBER   | JEDEC_TYPE | DESCRIPTION                         | MANUFTR | MANUF_PN         | RD_CMPLS_LVL | CMPLS_LVL | FROM_PJ     | CLASS | DIP_SMD | DATA                        | EE_CHECK_LIST | FP_ECN | PSL | CREATOR | STATUS | MSD | ESD_CDM | ESD_HBM | ESD_MM | PIN_LENGTH_SHORT_PIN | PIN_LENGTH_LONG_PIN | CREATEDAY  ;
{========================================================================================}
 'M24128-BWMN6TP' | 'SMLF'    | 'IC'     | 'AKE30Z00613'(!) = ''       | ''               | 'AKE30Z00613' |'SOIC8XH'| 'IC(8P) EEPROM M24128-BWMN6TP(SO8)' | 'SGT'   | 'M24128-BWMN6TP' | 'EP(V1)'     | 'EP(V1)'  | 'S2D-TERRY' | 'IC'  | ''      | 'SGT_M24256-B_M24128-B.pdf' | ''            | ''     | ''  | ''      | ''     | ''  | ''      | ''      | ''     | ''                   | ''                  | '20200318'
 'M24128-BWMN6TP' | 'SMLF'    | 'EMPTY'  | 'AKE30Z00613'(!) = ''       | ''               | 'AKE30Z00613' |'SOIC8XH'| 'IC(8P) EEPROM M24128-BWMN6TP(SO8)' | 'SGT'   | 'M24128-BWMN6TP' | 'EP(V1)'     | 'EP(V1)'  | 'S2D-TERRY' | 'IC'  | ''      | 'SGT_M24256-B_M24128-B.pdf' | ''            | ''     | ''  | ''      | ''     | ''  | ''      | ''      | ''     | ''                   | ''                  | '20200318'

END_PART

END.

